# T6G (Grand Teton) — schematic netlist excerpt (pin names and nets, part order shuffled) for the footprints in the layout excerpt that follows; sources: Cadence DE-HDL packaged netlist, KiCad conversion of 04192023_DAF0TMB3IC0_F0TG_MB_C_brd_V02_OCP.brd

J37  SCONN288_DDR506112002KQ  IO  pkg DDR288S_1-1VXC  page 109
  VIN_BULK0  = P12V_MEM_CPU1
  RFU0  = NC
  VIN_MGMT  = P3V3_AUX
  HSCL  = I3C_SPD_DDRL_CPU1_SCL
  HSDA  = I3C_SPD_DDRL_CPU1_SDA
  VSS0  = GND
  DQ0_A  = M_L_CPU1_SA_DQ<0>
  VSS1  = GND
  DQ1_A  = M_L_CPU1_SA_DQ<1>
  VSS2  = GND
  DQS0_A_T  = M_L_CPU1_SA_DQS_DP<0>
  DQS0_A_C  = M_L_CPU1_SA_DQS_DN<0>
  VSS3  = GND
  DQ4_A  = M_L_CPU1_SA_DQ<4>
  VSS4  = GND
  DQ5_A  = M_L_CPU1_SA_DQ<5>
  VSS5  = GND
  DQ8_A  = M_L_CPU1_SA_DQ<8>
  VSS6  = GND
  DQ9_A  = M_L_CPU1_SA_DQ<9>
  VSS7  = GND
  DQS1_A_T  = M_L_CPU1_SA_DQS_DP<1>
  DQS1_A_C  = M_L_CPU1_SA_DQS_DN<1>
  VSS8  = GND
  DQ12_A  = M_L_CPU1_SA_DQ<12>
  VSS9  = GND
  DQ13_A  = M_L_CPU1_SA_DQ<13>
  VSS10  = GND
  DQ16_A  = M_L_CPU1_SA_DQ<16>
  VSS11  = GND
  DQ17_A  = M_L_CPU1_SA_DQ<17>
  VSS12  = GND
  DQS2_A_T  = M_L_CPU1_SA_DQS_DP<2>
  DQS2_A_C  = M_L_CPU1_SA_DQS_DN<2>
  VSS13  = GND
  DQ20_A  = M_L_CPU1_SA_DQ<20>
  VSS14  = GND
  DQ21_A  = M_L_CPU1_SA_DQ<21>
  VSS15  = GND
  DQ24_A  = M_L_CPU1_SA_DQ<24>
  VSS16  = GND
  DQ25_A  = M_L_CPU1_SA_DQ<25>
  VSS17  = GND
  DQS3_A_T  = M_L_CPU1_SA_DQS_DP<3>
  DQS3_A_C  = M_L_CPU1_SA_DQS_DN<3>
  VSS18  = GND
  DQ28_A  = M_L_CPU1_SA_DQ<28>
  VSS19  = GND
  DQ29_A  = M_L_CPU1_SA_DQ<29>
  VSS20  = GND
  CB0_A  = M_L_CPU1_SA_CB<0>
  VSS21  = GND
  CB1_A  = M_L_CPU1_SA_CB<1>
  VSS22  = GND
  DQS4_A_T  = M_L_CPU1_SA_DQS_DP<4>
  DQS4_A_C  = M_L_CPU1_SA_DQS_DN<4>
  VSS23  = GND
  CB4_A  = M_L_CPU1_SA_CB<4>
  VSS24  = GND
  CB5_A  = M_L_CPU1_SA_CB<5>
  VSS25  = GND
  ALERT_N  = M_L_CPU1_ALERT_N
  VSS26  = GND
  CS0_A_N  = M_L_CPU1_SA_CS_N<0>
  VSS27  = GND
  CA0_A  = M_L_CPU1_SA_CA<0>
  VSS28  = GND
  CA2_A  = M_L_CPU1_SA_CA<2>
  VSS29  = GND
  CA4_A  = M_L_CPU1_SA_CA<4>
  VSS30  = GND
  CA6_A  = M_L_CPU1_SA_CA<6>
  VSS31  = GND
  PAR_A  = M_L_CPU1_SA_PAR
  VSS32  = GND
  CA0_B  = M_L_CPU1_SB_CA<0>
  VSS33  = GND
  CA2_B  = M_L_CPU1_SB_CA<2>
  VSS34  = GND
  CA4_B  = M_L_CPU1_SB_CA<4>
  VSS35  = GND
  CA6_B  = M_L_CPU1_SB_CA<6>
  VSS36  = GND
  CS0_B_N  = M_L_CPU1_SB_CS_N<0>
  VSS37  = GND
  \lbd||rsp_a_n\  = M_L_CPU1_SA_RSP<0>
  \lbs||rsp_b_n\  = M_L_CPU1_SB_RSP<0>
  VSS38  = GND
  CB4_B  = M_L_CPU1_SB_CB<4>
  VSS39  = GND
  CB5_B  = M_L_CPU1_SB_CB<5>
  VSS40  = GND
  \dqs9_b_t||tdqs9_b_t||dbi4_b_n\  = M_L_CPU1_SB_DQS_DP<9>
  \dqs9_b_c||tdqs9_b_c\  = M_L_CPU1_SB_DQS_DN<9>
  VSS41  = GND
  CB0_B  = M_L_CPU1_SB_CB<0>
  VSS42  = GND
  CB1_B  = M_L_CPU1_SB_CB<1>
  VSS43  = GND
  DQ0_B  = M_L_CPU1_SB_DQ<0>
  VSS44  = GND
  DQ1_B  = M_L_CPU1_SB_DQ<1>
  VSS45  = GND
  DQS0_B_T  = M_L_CPU1_SB_DQS_DP<0>
  DQS0_B_C  = M_L_CPU1_SB_DQS_DN<0>
  VSS46  = GND
  DQ4_B  = M_L_CPU1_SB_DQ<4>
  VSS47  = GND
  DQ5_B  = M_L_CPU1_SB_DQ<5>
  VSS48  = GND
  DQ8_B  = M_L_CPU1_SB_DQ<8>
  VSS49  = GND
  DQ9_B  = M_L_CPU1_SB_DQ<9>
  VSS50  = GND
  DQS1_B_T  = M_L_CPU1_SB_DQS_DP<1>
  DQS1_B_C  = M_L_CPU1_SB_DQS_DN<1>
  VSS51  = GND
  DQ12_B  = M_L_CPU1_SB_DQ<12>
  VSS52  = GND
  DQ13_B  = M_L_CPU1_SB_DQ<13>
  VSS53  = GND
  DQ16_B  = M_L_CPU1_SB_DQ<16>
  VSS54  = GND
  DQ17_B  = M_L_CPU1_SB_DQ<17>
  VSS55  = GND
  DQS2_B_T  = M_L_CPU1_SB_DQS_DP<2>
  DQS2_B_C  = M_L_CPU1_SB_DQS_DN<2>
  VSS56  = GND
  DQ20_B  = M_L_CPU1_SB_DQ<20>
  VSS57  = GND
  DQ21_B  = M_L_CPU1_SB_DQ<21>
  VSS58  = GND
  DQ24_B  = M_L_CPU1_SB_DQ<24>
  VSS59  = GND
  DQ25_B  = M_L_CPU1_SB_DQ<25>
  VSS60  = GND
  DQS3_B_T  = M_L_CPU1_SB_DQS_DP<3>
  DQS3_B_C  = M_L_CPU1_SB_DQS_DN<3>
  VSS61  = GND
  DQ28_B  = M_L_CPU1_SB_DQ<28>
  VSS62  = GND
  DQ29_B  = M_L_CPU1_SB_DQ<29>
  VSS63  = GND
  RFU1  = NC
  VIN_BULK1  = P12V_MEM_CPU1
  VIN_BULK2  = P12V_MEM_CPU1
  \pwr_good||fail_n\  = PWRGD_CHL_CPU1_DIMM
  HAS  = PD_CHL_CPU1_DIMM_SAA
  RFU2  = NC
  RFU3  = NC
  VSS64  = GND
  DQ2_A  = M_L_CPU1_SA_DQ<2>
  VSS65  = GND
  DQ3_A  = M_L_CPU1_SA_DQ<3>
  VSS66  = GND
  \dqs5_a_c||tdqs5_a_c||dqs5_a_t||tdqs5_a_t\  = M_L_CPU1_SA_DQS_DN<5>
  \dqs5_a_t||tdqs5_a_t\  = M_L_CPU1_SA_DQS_DP<5>
  VSS67  = GND
  DQ6_A  = M_L_CPU1_SA_DQ<6>
  VSS68  = GND
  DQ7_A  = M_L_CPU1_SA_DQ<7>
  VSS69  = GND
  DQ10_A  = M_L_CPU1_SA_DQ<10>
  VSS70  = GND
  DQ11_A  = M_L_CPU1_SA_DQ<11>
  VSS71  = GND
  \dqs6_a_c||tdqs6_a_c||dqs6_a_t||tdqs6_a_t\  = M_L_CPU1_SA_DQS_DN<6>
  \dqs6_a_t||tdqs6_a_t\  = M_L_CPU1_SA_DQS_DP<6>
  VSS72  = GND
  DQ14_A  = M_L_CPU1_SA_DQ<14>
  VSS73  = GND
  DQ15_A  = M_L_CPU1_SA_DQ<15>
  VSS74  = GND
  DQ18_A  = M_L_CPU1_SA_DQ<18>
  VSS75  = GND
  DQ19_A  = M_L_CPU1_SA_DQ<19>
  VSS76  = GND
  \dqs7_a_c||tdqs7_a_c\  = M_L_CPU1_SA_DQS_DN<7>
  \dqs7_a_t||tdqs7_a_t\  = M_L_CPU1_SA_DQS_DP<7>
  VSS77  = GND
  DQ22_A  = M_L_CPU1_SA_DQ<22>
  VSS78  = GND
  DQ23_A  = M_L_CPU1_SA_DQ<23>
  VSS79  = GND
  DQ26_A  = M_L_CPU1_SA_DQ<26>
  VSS80  = GND
  DQ27_A  = M_L_CPU1_SA_DQ<27>
  VSS81  = GND
  \dqs8_a_c||tdqs8_a_c\  = M_L_CPU1_SA_DQS_DN<8>
  \dqs8_a_t||tdqs8_a_t\  = M_L_CPU1_SA_DQS_DP<8>
  VSS82  = GND
  DQ30_A  = M_L_CPU1_SA_DQ<30>
  VSS83  = GND
  DQ31_A  = M_L_CPU1_SA_DQ<31>
  VSS84  = GND
  CB2_A  = M_L_CPU1_SA_CB<2>
  VSS85  = GND
  CB3_A  = M_L_CPU1_SA_CB<3>
  VSS86  = GND
  \dqs9_a_c||tdqs9_a_c\  = M_L_CPU1_SA_DQS_DN<9>
  \dqs9_a_t||tdqs9_a_t\  = M_L_CPU1_SA_DQS_DP<9>
  VSS87  = GND
  CB6_A  = M_L_CPU1_SA_CB<6>
  VSS88  = GND
  CB7_A  = M_L_CPU1_SA_CB<7>
  VSS89  = GND
  RESET_N  = M_L_CPU1_RESET_N
  VSS90  = GND
  CS1_A_N  = M_L_CPU1_SA_CS_N<1>
  VSS91  = GND
  CA1_A  = M_L_CPU1_SA_CA<1>
  VSS92  = GND
  CA3_A  = M_L_CPU1_SA_CA<3>
  VSS93  = GND
  CA5_A  = M_L_CPU1_SA_CA<5>
  VSS94  = GND
  CK_T  = M_L_CPU1_CLK_DP<0>
  CK_C  = M_L_CPU1_CLK_DN<0>
  VSS95  = GND
  RFU4  = NC
  CA1_B  = M_L_CPU1_SB_CA<1>
  VSS96  = GND
  CA3_B  = M_L_CPU1_SB_CA<3>
  VSS97  = GND
  CA5_B  = M_L_CPU1_SB_CA<5>
  VSS98  = GND
  PAR_B  = M_L_CPU1_SB_PAR
  VSS99  = GND
  CS1_B_N  = M_L_CPU1_SB_CS_N<1>
  VSS100  = GND
  RFU5  = NC
  RFU6  = NC
  VSS101  = GND
  CB6_B  = M_L_CPU1_SB_CB<6>
  VSS102  = GND
  CB7_B  = M_L_CPU1_SB_CB<7>
  VSS103  = GND
  DQS4_B_C  = M_L_CPU1_SB_DQS_DN<4>
  DQS4_B_T  = M_L_CPU1_SB_DQS_DP<4>
  VSS104  = GND
  CB2_B  = M_L_CPU1_SB_CB<2>
  VSS105  = GND
  CB3_B  = M_L_CPU1_SB_CB<3>
  VSS106  = GND
  DQ2_B  = M_L_CPU1_SB_DQ<2>
  VSS107  = GND
  DQ3_B  = M_L_CPU1_SB_DQ<3>
  VSS108  = GND
  \dqs5_b_c||tdqs5_b_c\  = M_L_CPU1_SB_DQS_DN<5>
  \dqs5_b_t||tdqs5_b_t\  = M_L_CPU1_SB_DQS_DP<5>
  VSS109  = GND
  DQ6_B  = M_L_CPU1_SB_DQ<6>
  VSS110  = GND
  DQ7_B  = M_L_CPU1_SB_DQ<7>
  VSS111  = GND
  DQ10_B  = M_L_CPU1_SB_DQ<10>
  VSS112  = GND
  DQ11_B  = M_L_CPU1_SB_DQ<11>
  VSS113  = GND
  \dqs6_b_c||tdqs6_b_c\  = M_L_CPU1_SB_DQS_DN<6>
  \dqs6_b_t||tdqs6_b_t\  = M_L_CPU1_SB_DQS_DP<6>
  VSS114  = GND
  DQ14_B  = M_L_CPU1_SB_DQ<14>
  VSS115  = GND
  DQ15_B  = M_L_CPU1_SB_DQ<15>
  VSS116  = GND
  DQ18_B  = M_L_CPU1_SB_DQ<18>
  VSS117  = GND
  DQ19_B  = M_L_CPU1_SB_DQ<19>
  VSS118  = GND
  \dqs7_b_c||tdqs7_b_c\  = M_L_CPU1_SB_DQS_DN<7>
  \dqs7_b_t||tdqs7_b_t\  = M_L_CPU1_SB_DQS_DP<7>
  VSS119  = GND
  DQ22_B  = M_L_CPU1_SB_DQ<22>
  VSS120  = GND
  DQ23_B  = M_L_CPU1_SB_DQ<23>
  VSS121  = GND
  DQ26_B  = M_L_CPU1_SB_DQ<26>
  VSS122  = GND
  DQ27_B  = M_L_CPU1_SB_DQ<27>
  VSS123  = GND
  \dqs8_b_c||tdqs8_b_c\  = M_L_CPU1_SB_DQS_DN<8>
  \dqs8_b_t||tdqs8_b_t\  = M_L_CPU1_SB_DQS_DP<8>
  VSS124  = GND
  DQ30_B  = M_L_CPU1_SB_DQ<30>
  VSS125  = GND
  DQ31_B  = M_L_CPU1_SB_DQ<31>
  VSS126  = GND
  G1  = GND
  G2  = GND
  G3  = GND

(kicad_pcb
	(version 20260206)
	(generator "pcbnew")
	(generator_version "10.0")
	(general
		(thickness 1.6)
		(legacy_teardrops no)
	)
	(paper "A4")
	(title_block
		(title "04192023_DAF0TMB3IC0_F0TG_MB_C_brd_V02_OCP.brd")
		(comment 1 "Grand Teton / footprint 34 of 8354 (J37), pads 93-138 of 291")
	)
	(layers
		(0 "F.Cu" signal "TOP")
		(4 "In1.Cu" signal "GND")
		(6 "In2.Cu" signal "IN1")
		(8 "In3.Cu" signal "GND1")
		(10 "In4.Cu" signal "IN2")
		(12 "In5.Cu" signal "GND2")
		(14 "In6.Cu" signal "IN3")
		(16 "In7.Cu" signal "GND3")
		(18 "In8.Cu" signal "VCC")
		(20 "In9.Cu" signal "VCC1")
		(22 "In10.Cu" signal "GND4")
		(24 "In11.Cu" signal "IN4")
		(26 "In12.Cu" signal "GND5")
		(28 "In13.Cu" signal "IN5")
		(30 "In14.Cu" signal "GND6")
		(32 "In15.Cu" signal "IN6")
		(34 "In16.Cu" signal "GND7")
		(2 "B.Cu" signal "BOTTOM")
		(9 "F.Adhes" user "F.Adhesive")
		(11 "B.Adhes" user "B.Adhesive")
		(13 "F.Paste" user "Package Geometry/Pastemask Top")
		(15 "B.Paste" user "Package Geometry/Pastemask Bottom")
		(5 "F.SilkS" user "Ref Des/Silkscreen Top")
		(7 "B.SilkS" user "Ref Des/Silkscreen Bottom")
		(1 "F.Mask" user "Board Geometry/Soldermask Top")
		(3 "B.Mask" user "Board Geometry/Soldermask Bottom")
		(17 "Dwgs.User" user "User.Drawings")
		(19 "Cmts.User" user "User.Comments")
		(21 "Eco1.User" user "User.Eco1")
		(23 "Eco2.User" user "User.Eco2")
		(25 "Edge.Cuts" user "Board Geometry/Outline")
		(27 "Margin" user)
		(31 "F.CrtYd" user "Package Geometry/Place Bound Top")
		(29 "B.CrtYd" user "Package Geometry/Place Bound Bottom")
		(35 "F.Fab" user "Ref Des/Assembly Top")
		(33 "B.Fab" user "Ref Des/Assembly Bottom")
	)
	(footprint ""
		(layer "F.Cu")
		(at 204.197966 -255.560322 180)
		(property "Reference" "J37"
			(at 2.8702 -81.730088 0)
			(unlocked yes)
			(layer "F.SilkS")
			(effects
				(font
					(size 0.7874 0.5842)
					(thickness 0.1524)
				)
			)
		)
		(property "Value" ""
			(at 0 0 180)
			(layer "F.Fab")
			(effects
				(font
					(size 1.27 1.27)
				)
			)
		)
		(duplicate_pad_numbers_are_jumpers no)
		(pad "93" smd rect
			(at -2.050034 19.975068 90)
			(size 0.519938 1.4986)
			(layers "F.Cu" "F.Mask" "F.Paste")
			(net "M_L_CPU1_SB_DQS_DP<9>")
		)
		(pad "94" smd rect
			(at -2.050034 20.824952 90)
			(size 0.519938 1.4986)
			(layers "F.Cu" "F.Mask" "F.Paste")
			(net "M_L_CPU1_SB_DQS_DN<9>")
		)
		(pad "95" smd rect
			(at -2.050034 21.67509 90)
			(size 0.519938 1.4986)
			(layers "F.Cu" "F.Mask" "F.Paste")
			(net "GND")
		)
		(pad "96" smd rect
			(at -2.050034 22.524974 90)
			(size 0.519938 1.4986)
			(layers "F.Cu" "F.Mask" "F.Paste")
			(net "M_L_CPU1_SB_CB<0>")
		)
		(pad "97" smd rect
			(at -2.050034 23.375112 90)
			(size 0.519938 1.4986)
			(layers "F.Cu" "F.Mask" "F.Paste")
			(net "GND")
		)
		(pad "98" smd rect
			(at -2.050034 24.224996 90)
			(size 0.519938 1.4986)
			(layers "F.Cu" "F.Mask" "F.Paste")
			(net "M_L_CPU1_SB_CB<1>")
		)
		(pad "99" smd rect
			(at -2.050034 25.07488 90)
			(size 0.519938 1.4986)
			(layers "F.Cu" "F.Mask" "F.Paste")
			(net "GND")
		)
		(pad "100" smd rect
			(at -2.050034 25.925018 90)
			(size 0.519938 1.4986)
			(layers "F.Cu" "F.Mask" "F.Paste")
			(net "M_L_CPU1_SB_DQ<0>")
		)
		(pad "101" smd rect
			(at -2.050034 26.774902 90)
			(size 0.519938 1.4986)
			(layers "F.Cu" "F.Mask" "F.Paste")
			(net "GND")
		)
		(pad "102" smd rect
			(at -2.050034 27.62504 90)
			(size 0.519938 1.4986)
			(layers "F.Cu" "F.Mask" "F.Paste")
			(net "M_L_CPU1_SB_DQ<1>")
		)
		(pad "103" smd rect
			(at -2.050034 28.474924 90)
			(size 0.519938 1.4986)
			(layers "F.Cu" "F.Mask" "F.Paste")
			(net "GND")
		)
		(pad "104" smd rect
			(at -2.050034 29.325062 90)
			(size 0.519938 1.4986)
			(layers "F.Cu" "F.Mask" "F.Paste")
			(net "M_L_CPU1_SB_DQS_DP<0>")
		)
		(pad "105" smd rect
			(at -2.050034 30.174946 90)
			(size 0.519938 1.4986)
			(layers "F.Cu" "F.Mask" "F.Paste")
			(net "M_L_CPU1_SB_DQS_DN<0>")
		)
		(pad "106" smd rect
			(at -2.050034 31.025084 90)
			(size 0.519938 1.4986)
			(layers "F.Cu" "F.Mask" "F.Paste")
			(net "GND")
		)
		(pad "107" smd rect
			(at -2.050034 31.874968 90)
			(size 0.519938 1.4986)
			(layers "F.Cu" "F.Mask" "F.Paste")
			(net "M_L_CPU1_SB_DQ<4>")
		)
		(pad "108" smd rect
			(at -2.050034 32.725106 90)
			(size 0.519938 1.4986)
			(layers "F.Cu" "F.Mask" "F.Paste")
			(net "GND")
		)
		(pad "109" smd rect
			(at -2.050034 33.57499 90)
			(size 0.519938 1.4986)
			(layers "F.Cu" "F.Mask" "F.Paste")
			(net "M_L_CPU1_SB_DQ<5>")
		)
		(pad "110" smd rect
			(at -2.050034 34.425128 90)
			(size 0.519938 1.4986)
			(layers "F.Cu" "F.Mask" "F.Paste")
			(net "GND")
		)
		(pad "111" smd rect
			(at -2.050034 35.275012 90)
			(size 0.519938 1.4986)
			(layers "F.Cu" "F.Mask" "F.Paste")
			(net "M_L_CPU1_SB_DQ<8>")
		)
		(pad "112" smd rect
			(at -2.050034 36.124896 90)
			(size 0.519938 1.4986)
			(layers "F.Cu" "F.Mask" "F.Paste")
			(net "GND")
		)
		(pad "113" smd rect
			(at -2.050034 36.975034 90)
			(size 0.519938 1.4986)
			(layers "F.Cu" "F.Mask" "F.Paste")
			(net "M_L_CPU1_SB_DQ<9>")
		)
		(pad "114" smd rect
			(at -2.050034 37.824918 90)
			(size 0.519938 1.4986)
			(layers "F.Cu" "F.Mask" "F.Paste")
			(net "GND")
		)
		(pad "115" smd rect
			(at -2.050034 38.675056 90)
			(size 0.519938 1.4986)
			(layers "F.Cu" "F.Mask" "F.Paste")
			(net "M_L_CPU1_SB_DQS_DP<1>")
		)
		(pad "116" smd rect
			(at -2.050034 39.52494 90)
			(size 0.519938 1.4986)
			(layers "F.Cu" "F.Mask" "F.Paste")
			(net "M_L_CPU1_SB_DQS_DN<1>")
		)
		(pad "117" smd rect
			(at -2.050034 40.375078 90)
			(size 0.519938 1.4986)
			(layers "F.Cu" "F.Mask" "F.Paste")
			(net "GND")
		)
		(pad "118" smd rect
			(at -2.050034 41.224962 90)
			(size 0.519938 1.4986)
			(layers "F.Cu" "F.Mask" "F.Paste")
			(net "M_L_CPU1_SB_DQ<12>")
		)
		(pad "119" smd rect
			(at -2.050034 42.0751 90)
			(size 0.519938 1.4986)
			(layers "F.Cu" "F.Mask" "F.Paste")
			(net "GND")
		)
		(pad "120" smd rect
			(at -2.050034 42.924984 90)
			(size 0.519938 1.4986)
			(layers "F.Cu" "F.Mask" "F.Paste")
			(net "M_L_CPU1_SB_DQ<13>")
		)
		(pad "121" smd rect
			(at -2.050034 43.775122 90)
			(size 0.519938 1.4986)
			(layers "F.Cu" "F.Mask" "F.Paste")
			(net "GND")
		)
		(pad "122" smd rect
			(at -2.050034 44.625006 90)
			(size 0.519938 1.4986)
			(layers "F.Cu" "F.Mask" "F.Paste")
			(net "M_L_CPU1_SB_DQ<16>")
		)
		(pad "123" smd rect
			(at -2.050034 45.47489 90)
			(size 0.519938 1.4986)
			(layers "F.Cu" "F.Mask" "F.Paste")
			(net "GND")
		)
		(pad "124" smd rect
			(at -2.050034 46.325028 90)
			(size 0.519938 1.4986)
			(layers "F.Cu" "F.Mask" "F.Paste")
			(net "M_L_CPU1_SB_DQ<17>")
		)
		(pad "125" smd rect
			(at -2.050034 47.174912 90)
			(size 0.519938 1.4986)
			(layers "F.Cu" "F.Mask" "F.Paste")
			(net "GND")
		)
		(pad "126" smd rect
			(at -2.050034 48.02505 90)
			(size 0.519938 1.4986)
			(layers "F.Cu" "F.Mask" "F.Paste")
			(net "M_L_CPU1_SB_DQS_DP<2>")
		)
		(pad "127" smd rect
			(at -2.050034 48.874934 90)
			(size 0.519938 1.4986)
			(layers "F.Cu" "F.Mask" "F.Paste")
			(net "M_L_CPU1_SB_DQS_DN<2>")
		)
		(pad "128" smd rect
			(at -2.050034 49.725072 90)
			(size 0.519938 1.4986)
			(layers "F.Cu" "F.Mask" "F.Paste")
			(net "GND")
		)
		(pad "129" smd rect
			(at -2.050034 50.574956 90)
			(size 0.519938 1.4986)
			(layers "F.Cu" "F.Mask" "F.Paste")
			(net "M_L_CPU1_SB_DQ<20>")
		)
		(pad "130" smd rect
			(at -2.050034 51.425094 90)
			(size 0.519938 1.4986)
			(layers "F.Cu" "F.Mask" "F.Paste")
			(net "GND")
		)
		(pad "131" smd rect
			(at -2.050034 52.274978 90)
			(size 0.519938 1.4986)
			(layers "F.Cu" "F.Mask" "F.Paste")
			(net "M_L_CPU1_SB_DQ<21>")
		)
		(pad "132" smd rect
			(at -2.050034 53.125116 90)
			(size 0.519938 1.4986)
			(layers "F.Cu" "F.Mask" "F.Paste")
			(net "GND")
		)
		(pad "133" smd rect
			(at -2.050034 53.975 90)
			(size 0.519938 1.4986)
			(layers "F.Cu" "F.Mask" "F.Paste")
			(net "M_L_CPU1_SB_DQ<24>")
		)
		(pad "134" smd rect
			(at -2.050034 54.824884 90)
			(size 0.519938 1.4986)
			(layers "F.Cu" "F.Mask" "F.Paste")
			(net "GND")
		)
		(pad "135" smd rect
			(at -2.050034 55.675022 90)
			(size 0.519938 1.4986)
			(layers "F.Cu" "F.Mask" "F.Paste")
			(net "M_L_CPU1_SB_DQ<25>")
		)
		(pad "136" smd rect
			(at -2.050034 56.524906 90)
			(size 0.519938 1.4986)
			(layers "F.Cu" "F.Mask" "F.Paste")
			(net "GND")
		)
		(pad "137" smd rect
			(at -2.050034 57.375044 90)
			(size 0.519938 1.4986)
			(layers "F.Cu" "F.Mask" "F.Paste")
			(net "M_L_CPU1_SB_DQS_DP<3>")
		)
		(pad "138" smd rect
			(at -2.050034 58.224928 90)
			(size 0.519938 1.4986)
			(layers "F.Cu" "F.Mask" "F.Paste")
			(net "M_L_CPU1_SB_DQS_DN<3>")
		)
	)
)
